(kicad_pcb
	(version 20241229)
	(generator "pcbnew")
	(generator_version "9.0")
	(general
		(thickness 1.711)
		(legacy_teardrops no)
	)
	(paper "A4")
	(title_block
		(title "Antmicro Baseboard for Jetson AGX Thor")
		(date "2026-02-18")
		(rev "1.1.0")
		(company "Antmicro Ltd")
		(comment 1 "www.antmicro.com")
		(comment 9 "footprints 356-359 of 1170")
	)
	(layers
		(0 "F.Cu" signal)
		(4 "In1.Cu" signal)
		(6 "In2.Cu" signal)
		(8 "In3.Cu" signal)
		(10 "In4.Cu" jumper)
		(12 "In5.Cu" signal)
		(14 "In6.Cu" signal)
		(16 "In7.Cu" signal)
		(18 "In8.Cu" signal)
		(2 "B.Cu" signal)
		(9 "F.Adhes" user "F.Adhesive")
		(11 "B.Adhes" user "B.Adhesive")
		(13 "F.Paste" user)
		(15 "B.Paste" user)
		(5 "F.SilkS" user "F.Silkscreen")
		(7 "B.SilkS" user "B.Silkscreen")
		(1 "F.Mask" user)
		(3 "B.Mask" user)
		(17 "Dwgs.User" user "User.Drawings")
		(19 "Cmts.User" user "User.Comments")
		(21 "Eco1.User" user "User.Eco1")
		(23 "Eco2.User" user "User.Eco2")
		(25 "Edge.Cuts" user)
		(27 "Margin" user)
		(31 "F.CrtYd" user "F.Courtyard")
		(29 "B.CrtYd" user "B.Courtyard")
		(35 "F.Fab" user)
		(33 "B.Fab" user)
	)
	(footprint "antmicro-footprints:USON-10_2.5x1mm_P0.5mm"
		(layer "F.Cu")
		(at 221.402132 86.512 180)
		(descr "USON-10 2.5x1mm_ Pitch 0.5mm")
		(tags "USON-10 2.5x1mm Pitch 0.5mm")
		(property "Reference" "U37"
			(at -1.14 1.15 90)
			(layer "F.SilkS")
			(effects
				(font
					(size 0.7 0.7)
					(thickness 0.15)
				)
				(justify right top)
			)
		)
		(property "Value" "TPD4E05U06QDQARQ1"
			(at 0.018 2.499 0)
			(layer "F.Fab")
			(effects
				(font
					(size 0.7 0.7)
					(thickness 0.15)
				)
				(justify right top)
			)
		)
		(property "Datasheet" "https://www.ti.com/lit/ds/symlink/tpd4e05u06-q1.pdf?HQS=dis-mous-null-mousermode-dsf-pf-null-wwe&ts=1663591265741&ref_url=https%253A%252F%252Fwww.mouser.com%252F"
			(at 0 0 0)
			(layer "F.Fab")
			(hide yes)
			(effects
				(font
					(size 1.27 1.27)
					(thickness 0.15)
				)
			)
		)
		(property "Description" "TVS diode array, 12 kV, USON-10, 5.5 V, 0.5 pF"
			(at 0 0 0)
			(layer "F.Fab")
			(hide yes)
			(effects
				(font
					(size 1.27 1.27)
					(thickness 0.15)
				)
			)
		)
		(property "Manufacturer" "Texas Instruments"
			(at 0 0 180)
			(unlocked yes)
			(layer "F.Fab")
			(hide yes)
			(effects
				(font
					(size 1 1)
					(thickness 0.15)
				)
			)
		)
		(property "MPN" "TPD4E05U06QDQARQ1"
			(at 0 0 180)
			(unlocked yes)
			(layer "F.Fab")
			(hide yes)
			(effects
				(font
					(size 1 1)
					(thickness 0.15)
				)
			)
		)
		(property "Author" "Antmicro"
			(at 0 0 180)
			(unlocked yes)
			(layer "F.Fab")
			(hide yes)
			(effects
				(font
					(size 1 1)
					(thickness 0.15)
				)
			)
		)
		(property "License" "Apache-2.0"
			(at 0 0 180)
			(unlocked yes)
			(layer "F.Fab")
			(hide yes)
			(effects
				(font
					(size 1 1)
					(thickness 0.15)
				)
			)
		)
		(sheetname "/USB DP Alt mode/")
		(sheetfile "usb_dp.kicad_sch")
		(attr smd)
		(fp_line
			(start 0.498 1.398)
			(end -0.5 1.398)
			(stroke
				(width 0.15)
				(type solid)
			)
			(layer "F.SilkS")
		)
		(fp_line
			(start 0.498 -1.401)
			(end -0.5 -1.401)
			(stroke
				(width 0.15)
				(type solid)
			)
			(layer "F.SilkS")
		)
		(fp_circle
			(center -0.68 -1.27)
			(end -0.63 -1.27)
			(stroke
				(width 0.15)
				(type solid)
			)
			(fill yes)
			(layer "F.SilkS")
		)
		(fp_rect
			(start -0.8 -1.5)
			(end 0.8 1.499)
			(stroke
				(width 0.05)
				(type solid)
			)
			(fill no)
			(layer "F.CrtYd")
		)
		(fp_line
			(start 0.498 -1.25)
			(end 0.498 1.249)
			(stroke
				(width 0.15)
				(type solid)
			)
			(layer "F.Fab")
		)
		(fp_line
			(start 0.498 -1.25)
			(end -0.25 -1.25)
			(stroke
				(width 0.15)
				(type solid)
			)
			(layer "F.Fab")
		)
		(fp_line
			(start -0.25 -1.25)
			(end -0.5 -1)
			(stroke
				(width 0.15)
				(type solid)
			)
			(layer "F.Fab")
		)
		(fp_line
			(start -0.5 1.249)
			(end 0.498 1.249)
			(stroke
				(width 0.15)
				(type solid)
			)
			(layer "F.Fab")
		)
		(fp_line
			(start -0.5 -1)
			(end -0.5 1.249)
			(stroke
				(width 0.15)
				(type solid)
			)
			(layer "F.Fab")
		)
		(fp_text user "Author: Antmicro"
			(at -0.802 5.7 0)
			(layer "F.Fab")
			(effects
				(font
					(size 0.7 0.7)
					(thickness 0.15)
				)
				(justify right top)
			)
		)
		(fp_text user "License: Apache-2.0"
			(at -0.802 6.9 0)
			(layer "F.Fab")
			(effects
				(font
					(size 0.7 0.7)
					(thickness 0.15)
				)
				(justify right top)
			)
		)
		(fp_text user "${REFERENCE}"
			(at -0.802 4.498 0)
			(layer "F.Fab")
			(effects
				(font
					(size 0.7 0.7)
					(thickness 0.15)
				)
				(justify right top)
			)
		)
		(pad "1" smd roundrect
			(at -0.387 -1 90)
			(size 0.25 0.55)
			(layers "F.Cu" "F.Mask" "F.Paste")
			(roundrect_rratio 0.25)
			(net 374 "/USB DP Alt mode/USBC1_CONN_TX2_N")
			(pintype "passive")
		)
		(pad "2" smd roundrect
			(at -0.387 -0.5 90)
			(size 0.25 0.55)
			(layers "F.Cu" "F.Mask" "F.Paste")
			(roundrect_rratio 0.25)
			(net 347 "/USB DP Alt mode/USBC1_CONN_TX2_P")
			(pintype "passive")
		)
		(pad "3" smd roundrect
			(at -0.387 0 90)
			(size 0.4 0.55)
			(layers "F.Cu" "F.Mask" "F.Paste")
			(roundrect_rratio 0.25)
			(net 1 "GND")
			(pintype "power_in")
		)
		(pad "4" smd roundrect
			(at -0.387 0.498 90)
			(size 0.25 0.55)
			(layers "F.Cu" "F.Mask" "F.Paste")
			(roundrect_rratio 0.25)
			(net 820 "/USB DP Alt mode/USBC1_RX2_N")
			(pintype "passive")
		)
		(pad "5" smd roundrect
			(at -0.387 0.998 90)
			(size 0.25 0.55)
			(layers "F.Cu" "F.Mask" "F.Paste")
			(roundrect_rratio 0.25)
			(net 818 "/USB DP Alt mode/USBC1_RX2_P")
			(pintype "passive")
		)
		(pad "6" smd roundrect
			(at 0.385 0.998 90)
			(size 0.25 0.55)
			(layers "F.Cu" "F.Mask" "F.Paste")
			(roundrect_rratio 0.25)
			(net 818 "/USB DP Alt mode/USBC1_RX2_P")
			(pintype "passive")
		)
		(pad "7" smd roundrect
			(at 0.385 0.498 90)
			(size 0.25 0.55)
			(layers "F.Cu" "F.Mask" "F.Paste")
			(roundrect_rratio 0.25)
			(net 820 "/USB DP Alt mode/USBC1_RX2_N")
			(pintype "passive")
		)
		(pad "8" smd roundrect
			(at 0.385 0 90)
			(size 0.4 0.55)
			(layers "F.Cu" "F.Mask" "F.Paste")
			(roundrect_rratio 0.25)
			(net 1 "GND")
			(pintype "passive")
		)
		(pad "9" smd roundrect
			(at 0.385 -0.5 90)
			(size 0.25 0.55)
			(layers "F.Cu" "F.Mask" "F.Paste")
			(roundrect_rratio 0.25)
			(net 347 "/USB DP Alt mode/USBC1_CONN_TX2_P")
			(pintype "passive")
		)
		(pad "10" smd roundrect
			(at 0.385 -1 90)
			(size 0.25 0.55)
			(layers "F.Cu" "F.Mask" "F.Paste")
			(roundrect_rratio 0.25)
			(net 374 "/USB DP Alt mode/USBC1_CONN_TX2_N")
			(pintype "passive")
		)
	)
	(footprint "antmicro-footprints:XDFN-2_1x0.60mm"
		(layer "F.Cu")
		(at 187.248 55.497999 -90)
		(property "Reference" "D37"
			(at 0.402001 0.548 90)
			(layer "F.SilkS")
			(effects
				(font
					(size 0.7 0.7)
					(thickness 0.15)
				)
				(justify left bottom)
			)
		)
		(property "Value" "TPD1E0B04_XDFN-2"
			(at 0 1.5 90)
			(layer "F.Fab")
			(effects
				(font
					(size 0.7 0.7)
					(thickness 0.15)
				)
				(justify right top)
			)
		)
		(property "Datasheet" "https://www.ti.com/general/docs/suppproductinfo.tsp?distId=26&gotoUrl=https://www.ti.com/lit/gpn/tpd1e0b04"
			(at 0 0 90)
			(layer "F.Fab")
			(hide yes)
			(effects
				(font
					(size 1.27 1.27)
					(thickness 0.15)
				)
			)
		)
		(property "Description" "Bidirectional TVS, 8 kV,  XDFN-2, 3.6 V, 0.18 pF"
			(at 0 0 90)
			(layer "F.Fab")
			(hide yes)
			(effects
				(font
					(size 1.27 1.27)
					(thickness 0.15)
				)
			)
		)
		(property "MPN" "TPD1E0B04DPYR"
			(at 0 0 90)
			(layer "F.Fab")
			(hide yes)
			(effects
				(font
					(size 1.27 1.27)
					(thickness 0.15)
				)
			)
		)
		(property "Manufacturer" "Texas Instruments"
			(at 0 0 90)
			(layer "F.Fab")
			(hide yes)
			(effects
				(font
					(size 1.27 1.27)
					(thickness 0.15)
				)
			)
		)
		(property "Author" "Antmicro"
			(at 0 0 270)
			(unlocked yes)
			(layer "F.Fab")
			(hide yes)
			(effects
				(font
					(size 1 1)
					(thickness 0.15)
				)
			)
		)
		(property "License" "Apache-2.0"
			(at 0 0 270)
			(unlocked yes)
			(layer "F.Fab")
			(hide yes)
			(effects
				(font
					(size 1 1)
					(thickness 0.15)
				)
			)
		)
		(sheetname "/Peripherals/")
		(sheetfile "peripherals.kicad_sch")
		(attr smd)
		(fp_poly
			(pts
				(xy -0.725 -0.475) (xy 0.725 -0.475) (xy 0.725 0.475) (xy -0.725 0.475)
			)
			(stroke
				(width 0.05)
				(type solid)
			)
			(fill no)
			(layer "F.CrtYd")
		)
		(fp_poly
			(pts
				(xy -0.55 -0.35) (xy 0.55 -0.35) (xy 0.55 0.35) (xy -0.55 0.35)
			)
			(stroke
				(width 0.15)
				(type solid)
			)
			(fill no)
			(layer "F.Fab")
		)
		(fp_text user "Author: Antmicro"
			(at -0.8 4.4 90)
			(layer "F.Fab")
			(effects
				(font
					(size 0.7 0.7)
					(thickness 0.15)
				)
				(justify right top)
			)
		)
		(fp_text user "${REFERENCE}"
			(at -0.8 3.2 90)
			(layer "F.Fab")
			(effects
				(font
					(size 0.7 0.7)
					(thickness 0.15)
				)
				(justify right top)
			)
		)
		(fp_text user "License: Apache-2.0"
			(at -0.799999 5.6 90)
			(layer "F.Fab")
			(effects
				(font
					(size 0.7 0.7)
					(thickness 0.15)
				)
				(justify right top)
			)
		)
		(pad "1" smd roundrect
			(at -0.350999 0 270)
			(size 0.3 0.5)
			(layers "F.Cu" "F.Mask" "F.Paste")
			(roundrect_rratio 0.25)
			(net 1 "GND")
			(pinfunction "C")
			(pintype "passive")
		)
		(pad "2" smd roundrect
			(at 0.349 0 270)
			(size 0.3 0.5)
			(layers "F.Cu" "F.Mask" "F.Paste")
			(roundrect_rratio 0.25)
			(net 448 "/Expansion connector/GPIO.USER_BTN0")
			(pinfunction "A")
			(pintype "passive")
		)
	)
	(footprint "antmicro-footprints:C_0402_1005Metric"
		(layer "F.Cu")
		(at 89.1 102.6 180)
		(descr "Capacitor SMD 0402")
		(tags "capacitor SMD 0402")
		(property "Reference" "C353"
			(at 3.8 -0.4 180)
			(layer "F.SilkS")
			(effects
				(font
					(size 0.7 0.7)
					(thickness 0.15)
				)
				(justify left bottom)
			)
		)
		(property "Value" "C_100n_0402"
			(at -1.022927 2.155213 180)
			(layer "F.Fab")
			(effects
				(font
					(size 0.7 0.7)
					(thickness 0.15)
				)
				(justify left bottom)
			)
		)
		(property "Datasheet" "https://www.murata.com/products/productdetail?partno=GRM155R61H104KE14%23"
			(at 0 0 180)
			(layer "F.Fab")
			(hide yes)
			(effects
				(font
					(size 1.27 1.27)
					(thickness 0.15)
				)
			)
		)
		(property "Description" "SMD Multilayer Ceramic Capacitor, 0.1 µF, 50 V, 0402 [1005 Metric], ± 10%, X5R, GRM Series"
			(at 0 0 180)
			(layer "F.Fab")
			(hide yes)
			(effects
				(font
					(size 1.27 1.27)
					(thickness 0.15)
				)
			)
		)
		(property "Manufacturer" "Murata"
			(at 0 0 180)
			(unlocked yes)
			(layer "F.Fab")
			(hide yes)
			(effects
				(font
					(size 1 1)
					(thickness 0.15)
				)
			)
		)
		(property "MPN" "GRM155R61H104KE14D"
			(at 0 0 180)
			(unlocked yes)
			(layer "F.Fab")
			(hide yes)
			(effects
				(font
					(size 1 1)
					(thickness 0.15)
				)
			)
		)
		(property "Val" "100n"
			(at 0 0 180)
			(unlocked yes)
			(layer "F.Fab")
			(hide yes)
			(effects
				(font
					(size 1 1)
					(thickness 0.15)
				)
			)
		)
		(property "License" "Apache-2.0"
			(at 0 0 180)
			(unlocked yes)
			(layer "F.Fab")
			(hide yes)
			(effects
				(font
					(size 1 1)
					(thickness 0.15)
				)
			)
		)
		(property "Author" "Antmicro"
			(at 0 0 180)
			(unlocked yes)
			(layer "F.Fab")
			(hide yes)
			(effects
				(font
					(size 1 1)
					(thickness 0.15)
				)
			)
		)
		(property "Voltage" "50V"
			(at 0 0 180)
			(unlocked yes)
			(layer "F.Fab")
			(hide yes)
			(effects
				(font
					(size 1 1)
					(thickness 0.15)
				)
			)
		)
		(property "Dielectric" "X5R"
			(at 0 0 180)
			(unlocked yes)
			(layer "F.Fab")
			(hide yes)
			(effects
				(font
					(size 1 1)
					(thickness 0.15)
				)
			)
		)
		(sheetname "/SoM_IO2/")
		(sheetfile "som_io2.kicad_sch")
		(attr smd)
		(fp_poly
			(pts
				(xy -0.925 -0.47) (xy 0.925 -0.47) (xy 0.925 0.47) (xy -0.925 0.47)
			)
			(stroke
				(width 0.05)
				(type default)
			)
			(fill no)
			(layer "F.CrtYd")
		)
		(fp_line
			(start 0.504 0.248)
			(end -0.494 0.248)
			(stroke
				(width 0.15)
				(type solid)
			)
			(layer "F.Fab")
		)
		(fp_line
			(start 0.504 -0.25)
			(end 0.504 0.248)
			(stroke
				(width 0.15)
				(type solid)
			)
			(layer "F.Fab")
		)
		(fp_line
			(start -0.494 0.248)
			(end -0.494 -0.25)
			(stroke
				(width 0.15)
				(type solid)
			)
			(layer "F.Fab")
		)
		(fp_line
			(start -0.494 -0.25)
			(end 0.504 -0.25)
			(stroke
				(width 0.15)
				(type solid)
			)
			(layer "F.Fab")
		)
		(fp_text user "License: Apache-2.0"
			(at -0.939 5.799 180)
			(layer "F.Fab")
			(effects
				(font
					(size 0.7 0.7)
					(thickness 0.15)
				)
				(justify left bottom)
			)
		)
		(fp_text user "${REFERENCE}"
			(at -0.939 4.599 180)
			(layer "F.Fab")
			(effects
				(font
					(size 0.7 0.7)
					(thickness 0.15)
				)
				(justify left bottom)
			)
		)
		(fp_text user "Author: Antmicro"
			(at -0.939 3.399 180)
			(layer "F.Fab")
			(effects
				(font
					(size 0.7 0.7)
					(thickness 0.15)
				)
				(justify left bottom)
			)
		)
		(pad "1" smd roundrect
			(at -0.48 0 180)
			(size 0.59 0.64)
			(layers "F.Cu" "F.Mask" "F.Paste")
			(roundrect_rratio 0.25)
			(net 1273 "/SoM_IO2/DP3.AUX_C-")
			(pintype "passive")
		)
		(pad "2" smd roundrect
			(at 0.48 0 180)
			(size 0.59 0.64)
			(layers "F.Cu" "F.Mask" "F.Paste")
			(roundrect_rratio 0.25)
			(net 657 "/Expansion connector/DP3.AUX-")
			(pintype "passive")
		)
	)
	(footprint "antmicro-footprints:L_WE-MAPI-4020"
		(layer "F.Cu")
		(at 146.814391 131.81)
		(property "Reference" "L7"
			(at 3.385609 0.59 270)
			(layer "F.SilkS")
			(effects
				(font
					(size 0.7 0.7)
					(thickness 0.15)
				)
				(justify left bottom)
			)
		)
		(property "Value" "L_1u8_6.8A_WE-MAPI-4020"
			(at -2.4 3.4 180)
			(layer "F.Fab")
			(effects
				(font
					(size 0.7 0.7)
					(thickness 0.15)
				)
				(justify left bottom)
			)
		)
		(property "Datasheet" "https://www.we-online.com/components/products/datasheet/74438356018.pdf"
			(at 0 0 0)
			(layer "F.Fab")
			(hide yes)
			(effects
				(font
					(size 1.27 1.27)
					(thickness 0.15)
				)
			)
		)
		(property "Description" "Power Inductors - SMD WE-MAPI 1.8uH 4.6A DCR=30mOhms AEC-Q200"
			(at 0 0 0)
			(layer "F.Fab")
			(hide yes)
			(effects
				(font
					(size 1.27 1.27)
					(thickness 0.15)
				)
			)
		)
		(property "Val" "1u8/6.8A"
			(at 0 0 0)
			(unlocked yes)
			(layer "F.Fab")
			(hide yes)
			(effects
				(font
					(size 1 1)
					(thickness 0.15)
				)
			)
		)
		(property "Manufacturer" "Würth Elektronik"
			(at 0 0 0)
			(unlocked yes)
			(layer "F.Fab")
			(hide yes)
			(effects
				(font
					(size 1 1)
					(thickness 0.15)
				)
			)
		)
		(property "MPN" "74438356018"
			(at 0 0 0)
			(unlocked yes)
			(layer "F.Fab")
			(hide yes)
			(effects
				(font
					(size 1 1)
					(thickness 0.15)
				)
			)
		)
		(property "ISat" "6.5 A"
			(at 0 0 0)
			(unlocked yes)
			(layer "F.Fab")
			(hide yes)
			(effects
				(font
					(size 1 1)
					(thickness 0.15)
				)
			)
		)
		(property "IMax" "6.8 A"
			(at 0 0 0)
			(unlocked yes)
			(layer "F.Fab")
			(hide yes)
			(effects
				(font
					(size 1 1)
					(thickness 0.15)
				)
			)
		)
		(property "Size" "4.1x4.1mm"
			(at 0 0 0)
			(unlocked yes)
			(layer "F.Fab")
			(hide yes)
			(effects
				(font
					(size 1 1)
					(thickness 0.15)
				)
			)
		)
		(property "Author" "Antmicro"
			(at 0 0 0)
			(unlocked yes)
			(layer "F.Fab")
			(hide yes)
			(effects
				(font
					(size 1 1)
					(thickness 0.15)
				)
			)
		)
		(property "License" "Apache-2.0"
			(at 0 0 0)
			(unlocked yes)
			(layer "F.Fab")
			(hide yes)
			(effects
				(font
					(size 1 1)
					(thickness 0.15)
				)
			)
		)
		(component_classes
			(class "DCDC_1V8")
		)
		(sheetname "/DCDC/")
		(sheetfile "dcdc.kicad_sch")
		(attr smd)
		(fp_rect
			(start -2.2 -2.2)
			(end 2.2 2.2)
			(stroke
				(width 0.15)
				(type solid)
			)
			(fill no)
			(layer "F.SilkS")
		)
		(fp_rect
			(start -2.3 -2.3)
			(end 2.3 2.3)
			(stroke
				(width 0.05)
				(type solid)
			)
			(fill no)
			(layer "F.CrtYd")
		)
		(fp_rect
			(start -2.05 -2.05)
			(end 2.05 2.05)
			(stroke
				(width 0.15)
				(type solid)
			)
			(fill no)
			(layer "F.Fab")
		)
		(fp_text user "Author: Antmicro"
			(at -2.4 6.6 0)
			(layer "F.Fab")
			(effects
				(font
					(size 0.7 0.7)
					(thickness 0.15)
				)
				(justify left bottom)
			)
		)
		(fp_text user "License: Apache-2.0"
			(at -2.4 5.4 0)
			(layer "F.Fab")
			(effects
				(font
					(size 0.7 0.7)
					(thickness 0.15)
				)
				(justify left bottom)
			)
		)
		(fp_text user "${REFERENCE}"
			(at -2.4 7.8 0)
			(layer "F.Fab")
			(effects
				(font
					(size 0.7 0.7)
					(thickness 0.15)
				)
				(justify left bottom)
			)
		)
		(pad "1" smd roundrect
			(at -1.185 0 90)
			(size 3.7 1)
			(layers "F.Cu" "F.Mask" "F.Paste")
			(roundrect_rratio 0.1)
			(net 1185 "/DCDC/1V8_SW")
			(pintype "passive")
		)
		(pad "2" smd roundrect
			(at 1.185 0 90)
			(size 3.7 1)
			(layers "F.Cu" "F.Mask" "F.Paste")
			(roundrect_rratio 0.1)
			(net 17 "/DCDC/1V8_OUT")
			(pintype "passive")
		)
	)
)
